# T6G (Grand Teton) — schematic netlist excerpt (pin names and nets, part order shuffled) for the footprints in the layout excerpt that follows; sources: Cadence DE-HDL packaged netlist, KiCad conversion of 04192023_DAF0TMB3IC0_F0TG_MB_C_brd_V02_OCP.brd

PC384  Q_CAP  3300PF 50V 10% X7R  pkg 0402  page 269 : A = P1V8_AUX_REF ; B = GND
R998  Q_RES  4.7K 5% CHIP  pkg 0201LF  page 276 : A = P1V8_CPU0_RT_1D ; B = MODE_RT_CPU0_P0
R1734  Q_RES  10K 1% CHIP  pkg 0402LF  page 171 : A = P3V3_AUX ; B = JTAG_SCM_TCK

(kicad_pcb
	(version 20260206)
	(generator "pcbnew")
	(generator_version "10.0")
	(general
		(thickness 1.6)
		(legacy_teardrops no)
	)
	(paper "A4")
	(title_block
		(title "04192023_DAF0TMB3IC0_F0TG_MB_C_brd_V02_OCP.brd")
		(comment 1 "Grand Teton / footprints 4771-4773 of 8354")
	)
	(layers
		(0 "F.Cu" signal "TOP")
		(4 "In1.Cu" signal "GND")
		(6 "In2.Cu" signal "IN1")
		(8 "In3.Cu" signal "GND1")
		(10 "In4.Cu" signal "IN2")
		(12 "In5.Cu" signal "GND2")
		(14 "In6.Cu" signal "IN3")
		(16 "In7.Cu" signal "GND3")
		(18 "In8.Cu" signal "VCC")
		(20 "In9.Cu" signal "VCC1")
		(22 "In10.Cu" signal "GND4")
		(24 "In11.Cu" signal "IN4")
		(26 "In12.Cu" signal "GND5")
		(28 "In13.Cu" signal "IN5")
		(30 "In14.Cu" signal "GND6")
		(32 "In15.Cu" signal "IN6")
		(34 "In16.Cu" signal "GND7")
		(2 "B.Cu" signal "BOTTOM")
		(9 "F.Adhes" user "F.Adhesive")
		(11 "B.Adhes" user "B.Adhesive")
		(13 "F.Paste" user "Package Geometry/Pastemask Top")
		(15 "B.Paste" user "Package Geometry/Pastemask Bottom")
		(5 "F.SilkS" user "Ref Des/Silkscreen Top")
		(7 "B.SilkS" user "Ref Des/Silkscreen Bottom")
		(1 "F.Mask" user "Board Geometry/Soldermask Top")
		(3 "B.Mask" user "Board Geometry/Soldermask Bottom")
		(17 "Dwgs.User" user "User.Drawings")
		(19 "Cmts.User" user "User.Comments")
		(21 "Eco1.User" user "User.Eco1")
		(23 "Eco2.User" user "User.Eco2")
		(25 "Edge.Cuts" user "Board Geometry/Outline")
		(27 "Margin" user)
		(31 "F.CrtYd" user "Package Geometry/Place Bound Top")
		(29 "B.CrtYd" user "Package Geometry/Place Bound Bottom")
		(35 "F.Fab" user "Ref Des/Assembly Top")
		(33 "B.Fab" user "Ref Des/Assembly Bottom")
	)
	(footprint ""
		(layer "F.Cu")
		(at 118.718584 -59.884056 180)
		(property "Reference" "R1734"
			(at 0 0 180)
			(layer "F.SilkS")
			(hide yes)
			(effects
				(font
					(size 1.27 1.27)
				)
			)
		)
		(property "Value" ""
			(at 0 0 180)
			(layer "F.Fab")
			(effects
				(font
					(size 1.27 1.27)
				)
			)
		)
		(duplicate_pad_numbers_are_jumpers no)
		(fp_line
			(start 0.7874 0.4064)
			(end -0.7874 0.4064)
			(stroke
				(width 0.1524)
				(type default)
			)
			(layer "F.SilkS")
		)
		(fp_line
			(start 0.7874 -0.4064)
			(end 0.7874 0.4064)
			(stroke
				(width 0.1524)
				(type default)
			)
			(layer "F.SilkS")
		)
		(fp_line
			(start -0.7874 0.4064)
			(end -0.7874 -0.4064)
			(stroke
				(width 0.1524)
				(type default)
			)
			(layer "F.SilkS")
		)
		(fp_line
			(start -0.7874 -0.4064)
			(end 0.7874 -0.4064)
			(stroke
				(width 0.1524)
				(type default)
			)
			(layer "F.SilkS")
		)
		(fp_line
			(start 0.67945 0.3048)
			(end 0.120396 0.3048)
			(stroke
				(width 0.1)
				(type default)
			)
			(layer "F.Fab")
		)
		(fp_line
			(start 0.67945 -0.3048)
			(end 0.67945 0.3048)
			(stroke
				(width 0.1)
				(type default)
			)
			(layer "F.Fab")
		)
		(fp_line
			(start 0.12065 -0.2794)
			(end 0.12065 -0.3048)
			(stroke
				(width 0.1)
				(type default)
			)
			(layer "F.Fab")
		)
		(fp_line
			(start 0.12065 -0.3048)
			(end 0.67945 -0.3048)
			(stroke
				(width 0.1)
				(type default)
			)
			(layer "F.Fab")
		)
		(fp_line
			(start 0.120396 0.3048)
			(end 0.120396 0.2794)
			(stroke
				(width 0.1)
				(type default)
			)
			(layer "F.Fab")
		)
		(fp_line
			(start 0.120396 0.2794)
			(end -0.12065 0.2794)
			(stroke
				(width 0.1)
				(type default)
			)
			(layer "F.Fab")
		)
		(fp_line
			(start -0.12065 0.3048)
			(end -0.67945 0.3048)
			(stroke
				(width 0.1)
				(type default)
			)
			(layer "F.Fab")
		)
		(fp_line
			(start -0.12065 0.2794)
			(end -0.12065 0.3048)
			(stroke
				(width 0.1)
				(type default)
			)
			(layer "F.Fab")
		)
		(fp_line
			(start -0.12065 -0.2794)
			(end 0.12065 -0.2794)
			(stroke
				(width 0.1)
				(type default)
			)
			(layer "F.Fab")
		)
		(fp_line
			(start -0.12065 -0.305054)
			(end -0.12065 -0.2794)
			(stroke
				(width 0.1)
				(type default)
			)
			(layer "F.Fab")
		)
		(fp_line
			(start -0.67945 0.3048)
			(end -0.67945 -0.305054)
			(stroke
				(width 0.1)
				(type default)
			)
			(layer "F.Fab")
		)
		(fp_line
			(start -0.67945 -0.305054)
			(end -0.12065 -0.305054)
			(stroke
				(width 0.1)
				(type default)
			)
			(layer "F.Fab")
		)
		(pad "1" smd circle
			(at -0.40005 0 180)
			(size 0 0)
			(layers "F.Cu" "F.Mask" "F.Paste")
			(net "P3V3_AUX")
		)
		(pad "2" smd circle
			(at 0.40005 0 180)
			(size 0 0)
			(layers "F.Cu" "F.Mask" "F.Paste")
			(net "JTAG_SCM_TCK")
		)
	)
	(footprint ""
		(layer "F.Cu")
		(at 144.4752 -75.557126 180)
		(property "Reference" "PC384"
			(at 0 0 180)
			(layer "F.SilkS")
			(hide yes)
			(effects
				(font
					(size 1.27 1.27)
				)
			)
		)
		(property "Value" ""
			(at 0 0 180)
			(layer "F.Fab")
			(effects
				(font
					(size 1.27 1.27)
				)
			)
		)
		(duplicate_pad_numbers_are_jumpers no)
		(fp_line
			(start 0.7874 0.4064)
			(end -0.7874 0.4064)
			(stroke
				(width 0.1524)
				(type default)
			)
			(layer "F.SilkS")
		)
		(fp_line
			(start 0.7874 -0.4064)
			(end 0.7874 0.4064)
			(stroke
				(width 0.1524)
				(type default)
			)
			(layer "F.SilkS")
		)
		(fp_line
			(start -0.7874 0.4064)
			(end -0.7874 -0.4064)
			(stroke
				(width 0.1524)
				(type default)
			)
			(layer "F.SilkS")
		)
		(fp_line
			(start -0.7874 -0.4064)
			(end 0.7874 -0.4064)
			(stroke
				(width 0.1524)
				(type default)
			)
			(layer "F.SilkS")
		)
		(fp_line
			(start 0.67945 0.3048)
			(end 0.120396 0.3048)
			(stroke
				(width 0.1)
				(type default)
			)
			(layer "F.Fab")
		)
		(fp_line
			(start 0.67945 -0.3048)
			(end 0.67945 0.3048)
			(stroke
				(width 0.1)
				(type default)
			)
			(layer "F.Fab")
		)
		(fp_line
			(start 0.12065 -0.2794)
			(end 0.12065 -0.3048)
			(stroke
				(width 0.1)
				(type default)
			)
			(layer "F.Fab")
		)
		(fp_line
			(start 0.12065 -0.3048)
			(end 0.67945 -0.3048)
			(stroke
				(width 0.1)
				(type default)
			)
			(layer "F.Fab")
		)
		(fp_line
			(start 0.120396 0.3048)
			(end 0.120396 0.2794)
			(stroke
				(width 0.1)
				(type default)
			)
			(layer "F.Fab")
		)
		(fp_line
			(start 0.120396 0.2794)
			(end -0.12065 0.2794)
			(stroke
				(width 0.1)
				(type default)
			)
			(layer "F.Fab")
		)
		(fp_line
			(start -0.12065 0.3048)
			(end -0.67945 0.3048)
			(stroke
				(width 0.1)
				(type default)
			)
			(layer "F.Fab")
		)
		(fp_line
			(start -0.12065 0.2794)
			(end -0.12065 0.3048)
			(stroke
				(width 0.1)
				(type default)
			)
			(layer "F.Fab")
		)
		(fp_line
			(start -0.12065 -0.2794)
			(end 0.12065 -0.2794)
			(stroke
				(width 0.1)
				(type default)
			)
			(layer "F.Fab")
		)
		(fp_line
			(start -0.12065 -0.305054)
			(end -0.12065 -0.2794)
			(stroke
				(width 0.1)
				(type default)
			)
			(layer "F.Fab")
		)
		(fp_line
			(start -0.67945 0.3048)
			(end -0.67945 -0.305054)
			(stroke
				(width 0.1)
				(type default)
			)
			(layer "F.Fab")
		)
		(fp_line
			(start -0.67945 -0.305054)
			(end -0.12065 -0.305054)
			(stroke
				(width 0.1)
				(type default)
			)
			(layer "F.Fab")
		)
		(pad "1" smd circle
			(at -0.40005 0 180)
			(size 0 0)
			(layers "F.Cu" "F.Mask" "F.Paste")
			(net "P1V8_AUX_REF")
		)
		(pad "2" smd circle
			(at 0.40005 0 180)
			(size 0 0)
			(layers "F.Cu" "F.Mask" "F.Paste")
			(net "GND")
		)
	)
	(footprint ""
		(layer "F.Cu")
		(at 296.385742 -398.78 90)
		(property "Reference" "R998"
			(at 0 0 90)
			(layer "F.SilkS")
			(hide yes)
			(effects
				(font
					(size 1.27 1.27)
				)
			)
		)
		(property "Value" ""
			(at 0 0 90)
			(layer "F.Fab")
			(effects
				(font
					(size 1.27 1.27)
				)
			)
		)
		(duplicate_pad_numbers_are_jumpers no)
		(fp_line
			(start 0.32512 -0.175006)
			(end 0.32512 0.175006)
			(stroke
				(width 0.1)
				(type default)
			)
			(layer "F.Fab")
		)
		(fp_line
			(start -0.32512 -0.175006)
			(end 0.32512 -0.175006)
			(stroke
				(width 0.1)
				(type default)
			)
			(layer "F.Fab")
		)
		(fp_line
			(start 0.32512 0.175006)
			(end -0.32512 0.175006)
			(stroke
				(width 0.1)
				(type default)
			)
			(layer "F.Fab")
		)
		(fp_line
			(start -0.32512 0.175006)
			(end -0.32512 -0.175006)
			(stroke
				(width 0.1)
				(type default)
			)
			(layer "F.Fab")
		)
		(pad "1" smd rect
			(at -0.2667 0 90)
			(size 0.3048 0.381)
			(layers "F.Cu" "F.Mask" "F.Paste")
			(net "P1V8_CPU0_RT_1D")
		)
		(pad "2" smd rect
			(at 0.2667 0 270)
			(size 0.3048 0.381)
			(layers "F.Cu" "F.Mask" "F.Paste")
			(net "MODE_RT_CPU0_P0")
		)
	)
)
